(kicad_pcb
	(version 20241229)
	(generator "pcbnew")
	(generator_version "9.0")
	(general
		(thickness 1.599998)
		(legacy_teardrops no)
	)
	(paper "A4")
	(title_block
		(title "Artix - Datacenter Secure Control Module (DC-SCM)")
		(date "2024-11-06")
		(rev "1.1.3")
		(comment 9 "footprints 128-132 of 544")
	)
	(layers
		(0 "F.Cu" signal)
		(4 "In1.Cu" signal)
		(6 "In2.Cu" signal)
		(8 "In3.Cu" signal)
		(10 "In4.Cu" signal)
		(12 "In5.Cu" signal)
		(14 "In6.Cu" signal)
		(2 "B.Cu" signal)
		(9 "F.Adhes" user "F.Adhesive")
		(11 "B.Adhes" user "B.Adhesive")
		(13 "F.Paste" user)
		(15 "B.Paste" user)
		(5 "F.SilkS" user "F.Silkscreen")
		(7 "B.SilkS" user "B.Silkscreen")
		(1 "F.Mask" user)
		(3 "B.Mask" user)
		(17 "Dwgs.User" user "User.Drawings")
		(19 "Cmts.User" user "User.Comments")
		(21 "Eco1.User" user "User.Eco1")
		(23 "Eco2.User" user "User.Eco2")
		(25 "Edge.Cuts" user)
		(27 "Margin" user)
		(31 "F.CrtYd" user "F.Courtyard")
		(29 "B.CrtYd" user "B.Courtyard")
		(35 "F.Fab" user)
		(33 "B.Fab" user)
	)
	(footprint "antmicro-footprints:R_0402_1005Metric"
		(layer "F.Cu")
		(at 73.15 87.867 180)
		(descr "Resistor SMD 0402")
		(tags "resistor SMD 0402")
		(property "Reference" "R190"
			(at -1.05 0.495 0)
			(layer "F.SilkS")
			(effects
				(font
					(size 0.7 0.7)
					(thickness 0.15)
				)
				(justify right bottom)
			)
		)
		(property "Value" "R_1k_0402"
			(at 0 1.4 0)
			(layer "F.Fab")
			(effects
				(font
					(size 0.7 0.7)
					(thickness 0.15)
				)
				(justify right bottom)
			)
		)
		(property "Datasheet" "https://www.bourns.com/docs/product-datasheets/cr.pdf"
			(at 0 0 180)
			(layer "F.Fab")
			(hide yes)
			(effects
				(font
					(size 1.27 1.27)
					(thickness 0.15)
				)
			)
		)
		(property "Description" "SMD Chip Resistor, 1 kohm, ± 1%, 63 mW, 0402 [1005 Metric], Thick Film, General Purpose"
			(at 0 0 180)
			(layer "F.Fab")
			(hide yes)
			(effects
				(font
					(size 1.27 1.27)
					(thickness 0.15)
				)
			)
		)
		(property "Author" "Antmicro"
			(at 146.3 175.734 0)
			(layer "F.Fab")
			(hide yes)
			(effects
				(font
					(size 1 1)
					(thickness 0.15)
				)
			)
		)
		(property "License" "Apache-2.0"
			(at 146.3 175.734 0)
			(layer "F.Fab")
			(hide yes)
			(effects
				(font
					(size 1 1)
					(thickness 0.15)
				)
			)
		)
		(property "MPN" "CR0402-FX-1001GLF"
			(at 146.3 175.734 0)
			(layer "F.Fab")
			(hide yes)
			(effects
				(font
					(size 1 1)
					(thickness 0.15)
				)
			)
		)
		(property "Manufacturer" "Bourns"
			(at 146.3 175.734 0)
			(layer "F.Fab")
			(hide yes)
			(effects
				(font
					(size 1 1)
					(thickness 0.15)
				)
			)
		)
		(property "Tolerance" "1%"
			(at 146.3 175.734 0)
			(layer "F.Fab")
			(hide yes)
			(effects
				(font
					(size 1 1)
					(thickness 0.15)
				)
			)
		)
		(property "Val" "1k"
			(at 146.3 175.734 0)
			(layer "F.Fab")
			(hide yes)
			(effects
				(font
					(size 1 1)
					(thickness 0.15)
				)
			)
		)
		(sheetname "/Power supply/")
		(sheetfile "power-supply.kicad_sch")
		(attr smd)
		(fp_rect
			(start -0.925 -0.47)
			(end 0.925 0.47)
			(stroke
				(width 0.05)
				(type default)
			)
			(fill no)
			(layer "F.CrtYd")
		)
		(fp_rect
			(start -0.5 -0.25)
			(end 0.5 0.25)
			(stroke
				(width 0.15)
				(type solid)
			)
			(fill no)
			(layer "F.Fab")
		)
		(pad "1" smd roundrect
			(at -0.48 0 180)
			(size 0.59 0.64)
			(layers "F.Cu" "F.Mask" "F.Paste")
			(roundrect_rratio 0.25)
			(net 340 "Net-(D14-A)")
			(pintype "passive")
		)
		(pad "2" smd roundrect
			(at 0.48 0 180)
			(size 0.59 0.64)
			(layers "F.Cu" "F.Mask" "F.Paste")
			(roundrect_rratio 0.25)
			(net 2 "VCC3V3")
			(pintype "passive")
		)
	)
	(footprint "antmicro-footprints:LED_0603_1608Metric_G"
		(layer "F.Cu")
		(at 75.719 87.857 180)
		(descr "LED SMD 0603 Green")
		(tags "LED SMD 0603 Green")
		(property "Reference" "D14"
			(at -3.381 -0.443 0)
			(layer "F.SilkS")
			(effects
				(font
					(size 0.7 0.7)
					(thickness 0.15)
				)
				(justify right bottom)
			)
		)
		(property "Value" "LED_G_0603_LG_L29K-G2J1-24-Z"
			(at 0 1.6 0)
			(layer "F.Fab")
			(effects
				(font
					(size 0.7 0.7)
					(thickness 0.15)
				)
				(justify right bottom)
			)
		)
		(property "Datasheet" "https://look.ams-osram.com/m/19ee86b3ae0ee95b/original/LG-L29K.pdf"
			(at 0 0 180)
			(layer "F.Fab")
			(hide yes)
			(effects
				(font
					(size 1.27 1.27)
					(thickness 0.15)
				)
			)
		)
		(property "Description" "LED, Green, SMD, 0603, 20 mA, 1.7 V, 570 nm"
			(at 0 0 180)
			(layer "F.Fab")
			(hide yes)
			(effects
				(font
					(size 1.27 1.27)
					(thickness 0.15)
				)
			)
		)
		(property "Author" "Antmicro"
			(at 151.438 175.714 0)
			(layer "F.Fab")
			(hide yes)
			(effects
				(font
					(size 1 1)
					(thickness 0.15)
				)
			)
		)
		(property "Color" "Green"
			(at 151.438 175.714 0)
			(layer "F.Fab")
			(hide yes)
			(effects
				(font
					(size 1 1)
					(thickness 0.15)
				)
			)
		)
		(property "License" "Apache-2.0"
			(at 151.438 175.714 0)
			(layer "F.Fab")
			(hide yes)
			(effects
				(font
					(size 1 1)
					(thickness 0.15)
				)
			)
		)
		(property "MPN" "LG L29K-G2J1-24-Z"
			(at 151.438 175.714 0)
			(layer "F.Fab")
			(hide yes)
			(effects
				(font
					(size 1 1)
					(thickness 0.15)
				)
			)
		)
		(property "Manufacturer" "OSRAM"
			(at 151.438 175.714 0)
			(layer "F.Fab")
			(hide yes)
			(effects
				(font
					(size 1 1)
					(thickness 0.15)
				)
			)
		)
		(sheetname "/Power supply/")
		(sheetfile "power-supply.kicad_sch")
		(attr smd)
		(fp_line
			(start 0.22 0.35)
			(end -0.22 0.35)
			(stroke
				(width 0.15)
				(type solid)
			)
			(layer "F.SilkS")
		)
		(fp_line
			(start 0.22 -0.35)
			(end -0.22 -0.35)
			(stroke
				(width 0.15)
				(type solid)
			)
			(layer "F.SilkS")
		)
		(fp_line
			(start 0.105328 0.201008)
			(end 0.105328 -0.198992)
			(stroke
				(width 0.1)
				(type solid)
			)
			(layer "F.SilkS")
		)
		(fp_line
			(start 0.105328 0.201008)
			(end -0.094672 0.001008)
			(stroke
				(width 0.1)
				(type solid)
			)
			(layer "F.SilkS")
		)
		(fp_line
			(start 0.105328 0.001008)
			(end 0.24 0.001)
			(stroke
				(width 0.1)
				(type solid)
			)
			(layer "F.SilkS")
		)
		(fp_line
			(start -0.094672 0.201008)
			(end -0.094672 -0.198992)
			(stroke
				(width 0.1)
				(type solid)
			)
			(layer "F.SilkS")
		)
		(fp_line
			(start -0.094672 0.001008)
			(end 0.105328 -0.198992)
			(stroke
				(width 0.1)
				(type solid)
			)
			(layer "F.SilkS")
		)
		(fp_line
			(start -0.094672 0.001008)
			(end -0.24 0.001008)
			(stroke
				(width 0.1)
				(type solid)
			)
			(layer "F.SilkS")
		)
		(fp_line
			(start -1.18 -0.319)
			(end -1.18 0.321)
			(stroke
				(width 0.15)
				(type solid)
			)
			(layer "F.SilkS")
		)
		(fp_rect
			(start 1.25 0.65)
			(end -1.25 -0.65)
			(stroke
				(width 0.05)
				(type solid)
			)
			(fill no)
			(layer "F.CrtYd")
		)
		(fp_line
			(start 0.599 0)
			(end 0.201 0)
			(stroke
				(width 0.15)
				(type solid)
			)
			(layer "F.Fab")
		)
		(fp_line
			(start 0.201 0.2)
			(end 0.201 0)
			(stroke
				(width 0.15)
				(type solid)
			)
			(layer "F.Fab")
		)
		(fp_line
			(start 0.201 0)
			(end 0.201 -0.202)
			(stroke
				(width 0.15)
				(type solid)
			)
			(layer "F.Fab")
		)
		(fp_line
			(start 0.201 -0.202)
			(end -0.101 0)
			(stroke
				(width 0.15)
				(type solid)
			)
			(layer "F.Fab")
		)
		(fp_line
			(start -0.101 0)
			(end 0.201 0.2)
			(stroke
				(width 0.15)
				(type solid)
			)
			(layer "F.Fab")
		)
		(fp_line
			(start -0.199 0.2)
			(end -0.199 0.1)
			(stroke
				(width 0.15)
				(type solid)
			)
			(layer "F.Fab")
		)
		(fp_line
			(start -0.199 0)
			(end -0.597 0)
			(stroke
				(width 0.15)
				(type solid)
			)
			(layer "F.Fab")
		)
		(fp_line
			(start -0.199 -0.202)
			(end -0.199 0.1)
			(stroke
				(width 0.15)
				(type solid)
			)
			(layer "F.Fab")
		)
		(fp_rect
			(start 0.848 0.4)
			(end -0.85 -0.402)
			(stroke
				(width 0.15)
				(type solid)
			)
			(fill no)
			(layer "F.Fab")
		)
		(pad "1" smd roundrect
			(at -0.7 0)
			(size 0.8 1)
			(layers "F.Cu" "F.Mask" "F.Paste")
			(roundrect_rratio 0.2)
			(net 313 "Net-(D14-C)")
			(pinfunction "C")
			(pintype "passive")
		)
		(pad "2" smd roundrect
			(at 0.7 0)
			(size 0.8 1)
			(layers "F.Cu" "F.Mask" "F.Paste")
			(roundrect_rratio 0.2)
			(net 340 "Net-(D14-A)")
			(pinfunction "A")
			(pintype "passive")
		)
	)
	(footprint "antmicro-footprints:C_0402_1005Metric"
		(layer "F.Cu")
		(at 68.739 97.057 90)
		(descr "Capacitor SMD 0402")
		(tags "capacitor SMD 0402")
		(property "Reference" "C64"
			(at -1.143 -0.639 90)
			(layer "F.SilkS")
			(effects
				(font
					(size 0.7 0.7)
					(thickness 0.15)
				)
				(justify left bottom)
			)
		)
		(property "Value" "C_10n_0402"
			(at 0 1.4 90)
			(layer "F.Fab")
			(effects
				(font
					(size 0.7 0.7)
					(thickness 0.15)
				)
				(justify left bottom)
			)
		)
		(property "Datasheet" "https://www.murata.com/products/productdetail?partno=GRM155R71H103KA88%23"
			(at 0 0 90)
			(layer "F.Fab")
			(hide yes)
			(effects
				(font
					(size 1.27 1.27)
					(thickness 0.15)
				)
			)
		)
		(property "Description" "SMD Multilayer Ceramic Capacitor, 10000 pF, 50 V, 0402 [1005 Metric], ± 10%, X7R, GRM Series"
			(at 0 0 90)
			(layer "F.Fab")
			(hide yes)
			(effects
				(font
					(size 1.27 1.27)
					(thickness 0.15)
				)
			)
		)
		(property "Author" "Antmicro"
			(at 165.796 28.318 0)
			(layer "F.Fab")
			(hide yes)
			(effects
				(font
					(size 1 1)
					(thickness 0.15)
				)
			)
		)
		(property "Dielectric" "X7R"
			(at 165.796 28.318 0)
			(layer "F.Fab")
			(hide yes)
			(effects
				(font
					(size 1 1)
					(thickness 0.15)
				)
			)
		)
		(property "License" "Apache-2.0"
			(at 165.796 28.318 0)
			(layer "F.Fab")
			(hide yes)
			(effects
				(font
					(size 1 1)
					(thickness 0.15)
				)
			)
		)
		(property "MPN" "GRM155R71H103KA88D"
			(at 165.796 28.318 0)
			(layer "F.Fab")
			(hide yes)
			(effects
				(font
					(size 1 1)
					(thickness 0.15)
				)
			)
		)
		(property "Manufacturer" "Murata"
			(at 165.796 28.318 0)
			(layer "F.Fab")
			(hide yes)
			(effects
				(font
					(size 1 1)
					(thickness 0.15)
				)
			)
		)
		(property "Val" "10n"
			(at 165.796 28.318 0)
			(layer "F.Fab")
			(hide yes)
			(effects
				(font
					(size 1 1)
					(thickness 0.15)
				)
			)
		)
		(property "Voltage" "50V"
			(at 165.796 28.318 0)
			(layer "F.Fab")
			(hide yes)
			(effects
				(font
					(size 1 1)
					(thickness 0.15)
				)
			)
		)
		(sheetname "/Power supply/")
		(sheetfile "power-supply.kicad_sch")
		(attr smd)
		(fp_rect
			(start -0.925 -0.47)
			(end 0.925 0.47)
			(stroke
				(width 0.05)
				(type default)
			)
			(fill no)
			(layer "F.CrtYd")
		)
		(fp_line
			(start 0.504 -0.25)
			(end 0.504 0.248)
			(stroke
				(width 0.15)
				(type solid)
			)
			(layer "F.Fab")
		)
		(fp_line
			(start -0.494 -0.25)
			(end 0.504 -0.25)
			(stroke
				(width 0.15)
				(type solid)
			)
			(layer "F.Fab")
		)
		(fp_line
			(start 0.504 0.248)
			(end -0.494 0.248)
			(stroke
				(width 0.15)
				(type solid)
			)
			(layer "F.Fab")
		)
		(fp_line
			(start -0.494 0.248)
			(end -0.494 -0.25)
			(stroke
				(width 0.15)
				(type solid)
			)
			(layer "F.Fab")
		)
		(pad "1" smd roundrect
			(at -0.48 0 90)
			(size 0.59 0.64)
			(layers "F.Cu" "F.Mask" "F.Paste")
			(roundrect_rratio 0.25)
			(net 1 "GND")
			(pintype "passive")
		)
		(pad "2" smd roundrect
			(at 0.48 0 90)
			(size 0.59 0.64)
			(layers "F.Cu" "F.Mask" "F.Paste")
			(roundrect_rratio 0.25)
			(net 103 "Net-(U9-TADJ)")
			(pintype "passive")
		)
	)
	(footprint "antmicro-footprints:C_0402_1005Metric"
		(layer "F.Cu")
		(at 107 144.6 -90)
		(descr "Capacitor SMD 0402")
		(tags "capacitor SMD 0402")
		(property "Reference" "C57"
			(at -3 -0.4 90)
			(layer "F.SilkS")
			(effects
				(font
					(size 0.7 0.7)
					(thickness 0.15)
				)
				(justify right bottom)
			)
		)
		(property "Value" "C_100n_6V3_0402"
			(at 0 1.4 90)
			(layer "F.Fab")
			(effects
				(font
					(size 0.7 0.7)
					(thickness 0.15)
				)
				(justify right bottom)
			)
		)
		(property "Datasheet" "https://www.passivecomponent.com/wp-content/uploads/datasheet/WTC_MLCC_General_Purpose.pdf"
			(at 0 0 270)
			(layer "F.Fab")
			(hide yes)
			(effects
				(font
					(size 1.27 1.27)
					(thickness 0.15)
				)
			)
		)
		(property "Description" "SMT Multilayer Ceramic Capacitor, 0.1 µF, 6.3 V, 0402 [1005 Metric], ± 10%, X5R, Walsin MLCC"
			(at 0 0 270)
			(layer "F.Fab")
			(hide yes)
			(effects
				(font
					(size 1.27 1.27)
					(thickness 0.15)
				)
			)
		)
		(property "Author" "Antmicro"
			(at -37.6 251.6 0)
			(layer "F.Fab")
			(hide yes)
			(effects
				(font
					(size 1 1)
					(thickness 0.15)
				)
			)
		)
		(property "Dielectric" ""
			(at -37.6 251.6 0)
			(layer "F.Fab")
			(hide yes)
			(effects
				(font
					(size 1 1)
					(thickness 0.15)
				)
			)
		)
		(property "License" "Apache-2.0"
			(at -37.6 251.6 0)
			(layer "F.Fab")
			(hide yes)
			(effects
				(font
					(size 1 1)
					(thickness 0.15)
				)
			)
		)
		(property "MPN" "0402X104K6R3CT"
			(at -37.6 251.6 0)
			(layer "F.Fab")
			(hide yes)
			(effects
				(font
					(size 1 1)
					(thickness 0.15)
				)
			)
		)
		(property "Manufacturer" "Walsin"
			(at -37.6 251.6 0)
			(layer "F.Fab")
			(hide yes)
			(effects
				(font
					(size 1 1)
					(thickness 0.15)
				)
			)
		)
		(property "Public" "False"
			(at -37.6 251.6 0)
			(layer "F.Fab")
			(hide yes)
			(effects
				(font
					(size 1 1)
					(thickness 0.15)
				)
			)
		)
		(property "Val" "100n"
			(at -37.6 251.6 0)
			(layer "F.Fab")
			(hide yes)
			(effects
				(font
					(size 1 1)
					(thickness 0.15)
				)
			)
		)
		(property "Voltage" ""
			(at -37.6 251.6 0)
			(layer "F.Fab")
			(hide yes)
			(effects
				(font
					(size 1 1)
					(thickness 0.15)
				)
			)
		)
		(sheetname "/DDR3/")
		(sheetfile "ddr3.kicad_sch")
		(attr smd)
		(fp_rect
			(start -0.925 -0.47)
			(end 0.925 0.47)
			(stroke
				(width 0.05)
				(type default)
			)
			(fill no)
			(layer "F.CrtYd")
		)
		(fp_line
			(start -0.494 0.248)
			(end -0.494 -0.25)
			(stroke
				(width 0.15)
				(type solid)
			)
			(layer "F.Fab")
		)
		(fp_line
			(start 0.504 0.248)
			(end -0.494 0.248)
			(stroke
				(width 0.15)
				(type solid)
			)
			(layer "F.Fab")
		)
		(fp_line
			(start -0.494 -0.25)
			(end 0.504 -0.25)
			(stroke
				(width 0.15)
				(type solid)
			)
			(layer "F.Fab")
		)
		(fp_line
			(start 0.504 -0.25)
			(end 0.504 0.248)
			(stroke
				(width 0.15)
				(type solid)
			)
			(layer "F.Fab")
		)
		(pad "1" smd roundrect
			(at -0.48 0 270)
			(size 0.59 0.64)
			(layers "F.Cu" "F.Mask" "F.Paste")
			(roundrect_rratio 0.25)
			(net 1 "GND")
			(pintype "passive")
		)
		(pad "2" smd roundrect
			(at 0.48 0 270)
			(size 0.59 0.64)
			(layers "F.Cu" "F.Mask" "F.Paste")
			(roundrect_rratio 0.25)
			(net 211 "DDR3_VREF")
			(pintype "passive")
		)
	)
	(footprint "antmicro-footprints:PinHeader_1x6_P2.54mm_Drill1.1mm"
		(layer "F.Cu")
		(at 65.126 106.675)
		(descr "WR-PHD 2.54mm Pin Header, 6 Pin")
		(property "Reference" "J7"
			(at -1.626 0.525 90)
			(layer "F.SilkS")
			(effects
				(font
					(size 0.7 0.7)
					(thickness 0.15)
				)
				(justify left bottom)
			)
		)
		(property "Value" "PinHeader_1x6_P2.54mm_Drill1.1mm"
			(at 0 2.45 0)
			(layer "F.Fab")
			(effects
				(font
					(size 0.7 0.7)
					(thickness 0.15)
				)
				(justify left bottom)
			)
		)
		(property "Datasheet" "https://www.we-online.com/components/products/datasheet/61300611121.pdf"
			(at 0 0 0)
			(layer "F.Fab")
			(hide yes)
			(effects
				(font
					(size 1.27 1.27)
					(thickness 0.15)
				)
			)
		)
		(property "Description" "Pin Header, Vertical, Board-to-Board, 2.54 mm, 1 Rows, 6 Contacts, Through Hole Straight, WR-PHD"
			(at 0 0 0)
			(layer "F.Fab")
			(hide yes)
			(effects
				(font
					(size 1.27 1.27)
					(thickness 0.15)
				)
			)
		)
		(property "Author" "Antmicro"
			(at 0 0 0)
			(layer "F.Fab")
			(hide yes)
			(effects
				(font
					(size 1 1)
					(thickness 0.15)
				)
			)
		)
		(property "License" "Apache-2.0"
			(at 0 0 0)
			(layer "F.Fab")
			(hide yes)
			(effects
				(font
					(size 1 1)
					(thickness 0.15)
				)
			)
		)
		(property "MPN" "61300611121"
			(at 0 0 0)
			(layer "F.Fab")
			(hide yes)
			(effects
				(font
					(size 1 1)
					(thickness 0.15)
				)
			)
		)
		(property "Manufacturer" "Würth Elektronik"
			(at 0 0 0)
			(layer "F.Fab")
			(hide yes)
			(effects
				(font
					(size 1 1)
					(thickness 0.15)
				)
			)
		)
		(sheetname "/Interfaces/")
		(sheetfile "interfaces.kicad_sch")
		(attr through_hole)
		(fp_line
			(start -1.272 -1.27)
			(end -1.272 1.269)
			(stroke
				(width 0.15)
				(type solid)
			)
			(layer "F.SilkS")
		)
		(fp_line
			(start -1.272 1.269)
			(end 13.968 1.269)
			(stroke
				(width 0.15)
				(type solid)
			)
			(layer "F.SilkS")
		)
		(fp_line
			(start 13.968 -1.27)
			(end -1.272 -1.27)
			(stroke
				(width 0.15)
				(type solid)
			)
			(layer "F.SilkS")
		)
		(fp_line
			(start 13.968 1.269)
			(end 13.968 -1.27)
			(stroke
				(width 0.15)
				(type solid)
			)
			(layer "F.SilkS")
		)
		(fp_line
			(start -1.5 -1.5)
			(end 14.18 -1.5)
			(stroke
				(width 0.05)
				(type solid)
			)
			(layer "F.CrtYd")
		)
		(fp_line
			(start -1.5 1.48)
			(end -1.5 -1.5)
			(stroke
				(width 0.05)
				(type solid)
			)
			(layer "F.CrtYd")
		)
		(fp_line
			(start 14.18 -1.5)
			(end 14.18 1.48)
			(stroke
				(width 0.05)
				(type solid)
			)
			(layer "F.CrtYd")
		)
		(fp_line
			(start 14.18 1.48)
			(end -1.5 1.48)
			(stroke
				(width 0.05)
				(type solid)
			)
			(layer "F.CrtYd")
		)
		(pad "1" thru_hole circle
			(at 0 0)
			(size 1.9 1.9)
			(drill 1.1)
			(layers "*.Cu" "*.Mask")
			(remove_unused_layers no)
			(net 2 "VCC3V3")
			(pintype "passive")
		)
		(pad "2" thru_hole circle
			(at 2.539 0)
			(size 1.9 1.9)
			(drill 1.1)
			(layers "*.Cu" "*.Mask")
			(remove_unused_layers no)
			(net 57 "SPI0_MOSI")
			(pintype "passive")
		)
		(pad "3" thru_hole circle
			(at 5.078 0)
			(size 1.9 1.9)
			(drill 1.1)
			(layers "*.Cu" "*.Mask")
			(remove_unused_layers no)
			(net 58 "SPI0_MISO")
			(pintype "passive")
		)
		(pad "4" thru_hole circle
			(at 7.618 0)
			(size 1.9 1.9)
			(drill 1.1)
			(layers "*.Cu" "*.Mask")
			(remove_unused_layers no)
			(net 56 "SPI0_CLK")
			(pintype "passive")
		)
		(pad "5" thru_hole circle
			(at 10.159 0)
			(size 1.9 1.9)
			(drill 1.1)
			(layers "*.Cu" "*.Mask")
			(remove_unused_layers no)
			(net 55 "SPI0_CS_N")
			(pintype "passive")
		)
		(pad "6" thru_hole circle
			(at 12.698 0)
			(size 1.9 1.9)
			(drill 1.1)
			(layers "*.Cu" "*.Mask")
			(remove_unused_layers no)
			(net 1 "GND")
			(pintype "passive")
		)
	)
)
